# BASEBOARD_FAB2 (Tioga Pass) — schematic netlist excerpt (pin names and nets, part order shuffled) for the footprints in the layout excerpt that follows; sources: Cadence DE-HDL packaged netlist, KiCad conversion of Wiwynn_Tioga_Pass_MB.brd

C3U5  CAPP  470UF 2.5V 20% ALUM  pkg 3018  page 217 : A = PVDDQ_ABC ; B = GND
C8P5  CAP  22UF 4V 20% X6S  pkg 0805LF  page 76 : A = PVSA_CPU1 ; B = GND
R2N13  RES  10.0K 1% CHIP  pkg 0402  page 147 : A = FM_BIOS_PREFRB2_GOOD ; B = GND

(kicad_pcb
	(version 20260206)
	(generator "pcbnew")
	(generator_version "10.0")
	(general
		(thickness 1.6)
		(legacy_teardrops no)
	)
	(paper "A4")
	(title_block
		(title "Wiwynn_Tioga_Pass_MB.brd")
		(comment 1 "Tioga Pass / footprints 4226-4228 of 4770")
	)
	(layers
		(0 "F.Cu" signal "TOP")
		(4 "In1.Cu" signal "L2GND")
		(6 "In2.Cu" signal "L3")
		(8 "In3.Cu" signal "L4GND")
		(10 "In4.Cu" signal "L5")
		(12 "In5.Cu" signal "L6GND")
		(14 "In6.Cu" signal "L7VCC")
		(16 "In7.Cu" signal "L8VCC")
		(18 "In8.Cu" signal "L9GND")
		(20 "In9.Cu" signal "L10")
		(22 "In10.Cu" signal "L11GND")
		(24 "In11.Cu" signal "L12")
		(26 "In12.Cu" signal "L13GND")
		(2 "B.Cu" signal "BOTTOM")
		(9 "F.Adhes" user "F.Adhesive")
		(11 "B.Adhes" user "B.Adhesive")
		(13 "F.Paste" user "Package Geometry/Pastemask Top")
		(15 "B.Paste" user "Package Geometry/Pastemask Bottom")
		(5 "F.SilkS" user "Ref Des/Silkscreen Top")
		(7 "B.SilkS" user "Ref Des/Silkscreen Bottom")
		(1 "F.Mask" user "Board Geometry/Soldermask Top")
		(3 "B.Mask" user "Board Geometry/Soldermask Bottom")
		(17 "Dwgs.User" user "User.Drawings")
		(19 "Cmts.User" user "User.Comments")
		(21 "Eco1.User" user "User.Eco1")
		(23 "Eco2.User" user "User.Eco2")
		(25 "Edge.Cuts" user "Board Geometry/Outline")
		(27 "Margin" user)
		(31 "F.CrtYd" user "Package Geometry/Place Bound Top")
		(29 "B.CrtYd" user "Package Geometry/Place Bound Bottom")
		(35 "F.Fab" user "Ref Des/Assembly Top")
		(33 "B.Fab" user "Ref Des/Assembly Bottom")
	)
	(footprint ""
		(layer "B.Cu")
		(at 97.270824 -83.74634 90)
		(property "Reference" "C8P5"
			(at 0 0 90)
			(layer "B.SilkS")
			(hide yes)
			(effects
				(font
					(size 1.27 1.27)
				)
				(justify mirror)
			)
		)
		(property "Value" ""
			(at 0 0 90)
			(layer "B.Fab")
			(effects
				(font
					(size 1.27 1.27)
				)
				(justify mirror)
			)
		)
		(duplicate_pad_numbers_are_jumpers no)
		(fp_poly
			(pts
				(xy 0.7239 -0.2159) (xy -0.7239 -0.2159) (xy -0.7239 1.9939) (xy 0.7239 1.9939)
			)
			(stroke
				(width 0)
				(type default)
			)
			(fill no)
			(layer "B.CrtYd")
		)
		(fp_line
			(start 0.7239 -0.2159)
			(end 0.7239 1.9939)
			(stroke
				(width 0.1)
				(type default)
			)
			(layer "B.Fab")
		)
		(fp_line
			(start -0.7239 -0.2159)
			(end 0.7239 -0.2159)
			(stroke
				(width 0.1)
				(type default)
			)
			(layer "B.Fab")
		)
		(fp_line
			(start 0.7239 1.9939)
			(end -0.7239 1.9939)
			(stroke
				(width 0.1)
				(type default)
			)
			(layer "B.Fab")
		)
		(fp_line
			(start -0.7239 1.9939)
			(end -0.7239 -0.2159)
			(stroke
				(width 0.1)
				(type default)
			)
			(layer "B.Fab")
		)
		(pad "1" smd rect
			(at 0 0 270)
			(size 1.27 1.016)
			(layers "B.Cu" "B.Mask" "B.Paste")
			(net "PVSA_CPU1")
		)
		(pad "2" smd rect
			(at 0 1.778 270)
			(size 1.27 1.016)
			(layers "B.Cu" "B.Mask" "B.Paste")
			(net "GND")
		)
		(zone
			(layer "B.Cu")
			(hatch none 0.5)
			(connect_pads
				(clearance 0)
			)
			(min_thickness 0.25)
			(keepout
				(tracks not_allowed)
				(vias allowed)
				(pads allowed)
				(copperpour not_allowed)
				(footprints allowed)
			)
			(placement
				(enabled no)
				(sheetname "")
			)
			(fill
				(thermal_gap 0.5)
				(thermal_bridge_width 0.5)
				(island_removal_mode 0)
			)
			(polygon
				(pts
					(xy 97.778824 -84.38134) (xy 97.778824 -83.11134) (xy 98.540824 -83.11134) (xy 98.540824 -84.38134)
				)
			)
		)
	)
	(footprint ""
		(layer "B.Cu")
		(at 334.01 -3.302 90)
		(property "Reference" "C3U5"
			(at 2.89433 4.572 0)
			(unlocked yes)
			(layer "B.SilkS")
			(effects
				(font
					(size 0.7874 0.5842)
					(thickness 0.1524)
				)
				(justify mirror)
			)
		)
		(property "Value" ""
			(at 0 0 90)
			(layer "B.Fab")
			(effects
				(font
					(size 1.27 1.27)
				)
				(justify mirror)
			)
		)
		(duplicate_pad_numbers_are_jumpers no)
		(fp_line
			(start 2.563114 -1.616456)
			(end 2.563114 1.633728)
			(stroke
				(width 0.1524)
				(type default)
			)
			(layer "B.SilkS")
		)
		(fp_line
			(start 1.6002 -1.616456)
			(end 2.563114 -1.616456)
			(stroke
				(width 0.1524)
				(type default)
			)
			(layer "B.SilkS")
		)
		(fp_line
			(start -1.6002 -1.616456)
			(end -2.504948 -1.616456)
			(stroke
				(width 0.1524)
				(type default)
			)
			(layer "B.SilkS")
		)
		(fp_line
			(start -2.504948 -1.616456)
			(end -2.504948 1.633728)
			(stroke
				(width 0.1524)
				(type default)
			)
			(layer "B.SilkS")
		)
		(fp_line
			(start 2.563114 1.633728)
			(end 1.6002 1.633728)
			(stroke
				(width 0.1524)
				(type default)
			)
			(layer "B.SilkS")
		)
		(fp_line
			(start -2.504948 1.633728)
			(end -1.6002 1.633728)
			(stroke
				(width 0.1524)
				(type default)
			)
			(layer "B.SilkS")
		)
		(fp_line
			(start 2.286 7.366)
			(end 2.286 1.632712)
			(stroke
				(width 0.1524)
				(type default)
			)
			(layer "B.SilkS")
		)
		(fp_line
			(start 2.286 7.366)
			(end 1.60147 7.366)
			(stroke
				(width 0.1524)
				(type default)
			)
			(layer "B.SilkS")
		)
		(fp_line
			(start -2.286 7.366)
			(end -2.286 1.63195)
			(stroke
				(width 0.1524)
				(type default)
			)
			(layer "B.SilkS")
		)
		(fp_line
			(start -2.286 7.366)
			(end -1.600708 7.366)
			(stroke
				(width 0.1524)
				(type default)
			)
			(layer "B.SilkS")
		)
		(fp_rect
			(start -2.286 -0.254)
			(end 2.286 7.366)
			(stroke
				(width 0)
				(type default)
			)
			(fill no)
			(layer "B.CrtYd")
		)
		(fp_line
			(start 2.286 -0.254)
			(end -2.286 -0.254)
			(stroke
				(width 0.1)
				(type default)
			)
			(layer "B.Fab")
		)
		(fp_line
			(start -2.286 -0.254)
			(end -2.286 7.366)
			(stroke
				(width 0.1)
				(type default)
			)
			(layer "B.Fab")
		)
		(fp_line
			(start 2.286 7.366)
			(end 2.286 -0.254)
			(stroke
				(width 0.1)
				(type default)
			)
			(layer "B.Fab")
		)
		(fp_line
			(start -2.286 7.366)
			(end 2.286 7.366)
			(stroke
				(width 0.1)
				(type default)
			)
			(layer "B.Fab")
		)
		(pad "1" smd rect
			(at 0 0 270)
			(size 2.54 3.048)
			(layers "B.Cu" "B.Mask" "B.Paste")
			(net "PVDDQ_ABC")
		)
		(pad "2" smd rect
			(at 0 7.112 270)
			(size 2.54 3.048)
			(layers "B.Cu" "B.Mask" "B.Paste")
			(net "GND")
		)
	)
	(footprint ""
		(layer "B.Cu")
		(at 427.4185 -24.13 90)
		(property "Reference" "R2N13"
			(at 0.8382 -0.67818 90)
			(unlocked yes)
			(layer "B.SilkS")
			(effects
				(font
					(size 0.4064 0.254)
					(thickness 0.1524)
				)
				(justify left mirror)
			)
		)
		(property "Value" ""
			(at 0 0 90)
			(layer "B.Fab")
			(effects
				(font
					(size 1.27 1.27)
				)
				(justify mirror)
			)
		)
		(duplicate_pad_numbers_are_jumpers no)
		(fp_poly
			(pts
				(xy 0.2794 -0.1016) (xy -0.2794 -0.1016) (xy -0.2794 0.9906) (xy 0.2794 0.9906)
			)
			(stroke
				(width 0)
				(type default)
			)
			(fill no)
			(layer "B.CrtYd")
		)
		(fp_line
			(start 0.2794 -0.1016)
			(end 0.2794 0.9906)
			(stroke
				(width 0.1)
				(type default)
			)
			(layer "B.Fab")
		)
		(fp_line
			(start -0.2794 -0.1016)
			(end 0.2794 -0.1016)
			(stroke
				(width 0.1)
				(type default)
			)
			(layer "B.Fab")
		)
		(fp_line
			(start 0.2794 0.9906)
			(end -0.2794 0.9906)
			(stroke
				(width 0.1)
				(type default)
			)
			(layer "B.Fab")
		)
		(fp_line
			(start -0.2794 0.9906)
			(end -0.2794 -0.1016)
			(stroke
				(width 0.1)
				(type default)
			)
			(layer "B.Fab")
		)
		(pad "1" smd rect
			(at 0 0 270)
			(size 0.508 0.508)
			(layers "B.Cu" "B.Mask" "B.Paste")
			(net "FM_BIOS_PREFRB2_GOOD")
		)
		(pad "2" smd rect
			(at 0 0.889 270)
			(size 0.508 0.508)
			(layers "B.Cu" "B.Mask" "B.Paste")
			(net "GND")
		)
		(zone
			(layer "B.Cu")
			(hatch none 0.5)
			(connect_pads
				(clearance 0)
			)
			(min_thickness 0.25)
			(keepout
				(tracks allowed)
				(vias not_allowed)
				(pads allowed)
				(copperpour not_allowed)
				(footprints allowed)
			)
			(placement
				(enabled no)
				(sheetname "")
			)
			(fill
				(thermal_gap 0.5)
				(thermal_bridge_width 0.5)
				(island_removal_mode 0)
			)
			(polygon
				(pts
					(xy 427.6725 -24.384) (xy 427.6725 -23.876) (xy 428.0535 -23.876) (xy 428.0535 -24.384)
				)
			)
		)
		(zone
			(layer "B.Cu")
			(hatch none 0.5)
			(connect_pads
				(clearance 0)
			)
			(min_thickness 0.25)
			(keepout
				(tracks not_allowed)
				(vias allowed)
				(pads allowed)
				(copperpour not_allowed)
				(footprints allowed)
			)
			(placement
				(enabled no)
				(sheetname "")
			)
			(fill
				(thermal_gap 0.5)
				(thermal_bridge_width 0.5)
				(island_removal_mode 0)
			)
			(polygon
				(pts
					(xy 428.0535 -24.384) (xy 428.0535 -23.876) (xy 427.6725 -23.876) (xy 427.6725 -24.384)
				)
			)
		)
	)
)
